# S9S_MB_2U (Grand Teton) — schematic netlist excerpt (pin names and nets, part order shuffled) for the footprints in the layout excerpt that follows; sources: Cadence DE-HDL packaged netlist, KiCad conversion of 03242023_DA0F0TMBIJ0_F0T_Motherboard_J_brd_V01_OCP.brd

R2312  Q_RES  10K 1% CHIP  pkg 0402LF  page 236 : A = P3V3_AUX ; B = PCA9545_S3M_INT_N
R1750  Q_RES  1K 1% CHIP  pkg 0402LF  page 202 : A = PGPPA_AUX ; B = FM_ESPI_PLD_R_EN_BUF

(kicad_pcb
	(version 20260206)
	(generator "pcbnew")
	(generator_version "10.0")
	(general
		(thickness 1.6)
		(legacy_teardrops no)
	)
	(paper "A4")
	(title_block
		(title "03242023_DA0F0TMBIJ0_F0T_Motherboard_J_brd_V01_OCP.brd")
		(comment 1 "Grand Teton / footprints 1428-1429 of 6105")
	)
	(layers
		(0 "F.Cu" signal "TOP")
		(4 "In1.Cu" signal "GND")
		(6 "In2.Cu" signal "IN1")
		(8 "In3.Cu" signal "GND1")
		(10 "In4.Cu" signal "IN2")
		(12 "In5.Cu" signal "GND2")
		(14 "In6.Cu" signal "IN3")
		(16 "In7.Cu" signal "GND3")
		(18 "In8.Cu" signal "VCC")
		(20 "In9.Cu" signal "VCC1")
		(22 "In10.Cu" signal "GND4")
		(24 "In11.Cu" signal "IN4")
		(26 "In12.Cu" signal "GND5")
		(28 "In13.Cu" signal "IN5")
		(30 "In14.Cu" signal "GND6")
		(32 "In15.Cu" signal "IN6")
		(34 "In16.Cu" signal "GND7")
		(2 "B.Cu" signal "BOTTOM")
		(9 "F.Adhes" user "F.Adhesive")
		(11 "B.Adhes" user "B.Adhesive")
		(13 "F.Paste" user "Package Geometry/Pastemask Top")
		(15 "B.Paste" user "Package Geometry/Pastemask Bottom")
		(5 "F.SilkS" user "Ref Des/Silkscreen Top")
		(7 "B.SilkS" user "Ref Des/Silkscreen Bottom")
		(1 "F.Mask" user "Board Geometry/Soldermask Top")
		(3 "B.Mask" user "Board Geometry/Soldermask Bottom")
		(17 "Dwgs.User" user "User.Drawings")
		(19 "Cmts.User" user "User.Comments")
		(21 "Eco1.User" user "User.Eco1")
		(23 "Eco2.User" user "User.Eco2")
		(25 "Edge.Cuts" user "Board Geometry/Outline")
		(27 "Margin" user)
		(31 "F.CrtYd" user "Package Geometry/Place Bound Top")
		(29 "B.CrtYd" user "Package Geometry/Place Bound Bottom")
		(35 "F.Fab" user "Ref Des/Assembly Top")
		(33 "B.Fab" user "Ref Des/Assembly Bottom")
	)
	(footprint ""
		(layer "F.Cu")
		(at 148.98243 -75.350878)
		(property "Reference" "R2312"
			(at 0 0 0)
			(layer "F.SilkS")
			(hide yes)
			(effects
				(font
					(size 1.27 1.27)
				)
			)
		)
		(property "Value" ""
			(at 0 0 0)
			(layer "F.Fab")
			(effects
				(font
					(size 1.27 1.27)
				)
			)
		)
		(duplicate_pad_numbers_are_jumpers no)
		(fp_line
			(start -0.7874 -0.4064)
			(end 0.7874 -0.4064)
			(stroke
				(width 0.1524)
				(type default)
			)
			(layer "F.SilkS")
		)
		(fp_line
			(start -0.7874 0.4064)
			(end -0.7874 -0.4064)
			(stroke
				(width 0.1524)
				(type default)
			)
			(layer "F.SilkS")
		)
		(fp_line
			(start 0.7874 -0.4064)
			(end 0.7874 0.4064)
			(stroke
				(width 0.1524)
				(type default)
			)
			(layer "F.SilkS")
		)
		(fp_line
			(start 0.7874 0.4064)
			(end -0.7874 0.4064)
			(stroke
				(width 0.1524)
				(type default)
			)
			(layer "F.SilkS")
		)
		(fp_line
			(start -0.67945 -0.305054)
			(end -0.12065 -0.305054)
			(stroke
				(width 0.1)
				(type default)
			)
			(layer "F.Fab")
		)
		(fp_line
			(start -0.67945 0.3048)
			(end -0.67945 -0.305054)
			(stroke
				(width 0.1)
				(type default)
			)
			(layer "F.Fab")
		)
		(fp_line
			(start -0.12065 -0.305054)
			(end -0.12065 -0.2794)
			(stroke
				(width 0.1)
				(type default)
			)
			(layer "F.Fab")
		)
		(fp_line
			(start -0.12065 -0.2794)
			(end 0.12065 -0.2794)
			(stroke
				(width 0.1)
				(type default)
			)
			(layer "F.Fab")
		)
		(fp_line
			(start -0.12065 0.2794)
			(end -0.12065 0.3048)
			(stroke
				(width 0.1)
				(type default)
			)
			(layer "F.Fab")
		)
		(fp_line
			(start -0.12065 0.3048)
			(end -0.67945 0.3048)
			(stroke
				(width 0.1)
				(type default)
			)
			(layer "F.Fab")
		)
		(fp_line
			(start 0.120396 0.2794)
			(end -0.12065 0.2794)
			(stroke
				(width 0.1)
				(type default)
			)
			(layer "F.Fab")
		)
		(fp_line
			(start 0.120396 0.3048)
			(end 0.120396 0.2794)
			(stroke
				(width 0.1)
				(type default)
			)
			(layer "F.Fab")
		)
		(fp_line
			(start 0.12065 -0.3048)
			(end 0.67945 -0.3048)
			(stroke
				(width 0.1)
				(type default)
			)
			(layer "F.Fab")
		)
		(fp_line
			(start 0.12065 -0.2794)
			(end 0.12065 -0.3048)
			(stroke
				(width 0.1)
				(type default)
			)
			(layer "F.Fab")
		)
		(fp_line
			(start 0.67945 -0.3048)
			(end 0.67945 0.3048)
			(stroke
				(width 0.1)
				(type default)
			)
			(layer "F.Fab")
		)
		(fp_line
			(start 0.67945 0.3048)
			(end 0.120396 0.3048)
			(stroke
				(width 0.1)
				(type default)
			)
			(layer "F.Fab")
		)
		(pad "1" smd circle
			(at -0.40005 0)
			(size 0 0)
			(layers "F.Cu" "F.Mask" "F.Paste")
			(net "P3V3_AUX")
		)
		(pad "2" smd circle
			(at 0.40005 0)
			(size 0 0)
			(layers "F.Cu" "F.Mask" "F.Paste")
			(net "PCA9545_S3M_INT_N")
		)
	)
	(footprint ""
		(layer "F.Cu")
		(at 334.729074 -16.2052 -90)
		(property "Reference" "R1750"
			(at 0 0 270)
			(layer "F.SilkS")
			(hide yes)
			(effects
				(font
					(size 1.27 1.27)
				)
			)
		)
		(property "Value" ""
			(at 0 0 270)
			(layer "F.Fab")
			(effects
				(font
					(size 1.27 1.27)
				)
			)
		)
		(duplicate_pad_numbers_are_jumpers no)
		(fp_line
			(start -0.7874 0.4064)
			(end -0.7874 -0.4064)
			(stroke
				(width 0.1524)
				(type default)
			)
			(layer "F.SilkS")
		)
		(fp_line
			(start 0.7874 0.4064)
			(end -0.7874 0.4064)
			(stroke
				(width 0.1524)
				(type default)
			)
			(layer "F.SilkS")
		)
		(fp_line
			(start -0.7874 -0.4064)
			(end 0.7874 -0.4064)
			(stroke
				(width 0.1524)
				(type default)
			)
			(layer "F.SilkS")
		)
		(fp_line
			(start 0.7874 -0.4064)
			(end 0.7874 0.4064)
			(stroke
				(width 0.1524)
				(type default)
			)
			(layer "F.SilkS")
		)
		(fp_line
			(start -0.67945 0.3048)
			(end -0.67945 -0.305054)
			(stroke
				(width 0.1)
				(type default)
			)
			(layer "F.Fab")
		)
		(fp_line
			(start -0.12065 0.3048)
			(end -0.67945 0.3048)
			(stroke
				(width 0.1)
				(type default)
			)
			(layer "F.Fab")
		)
		(fp_line
			(start 0.120396 0.3048)
			(end 0.120396 0.2794)
			(stroke
				(width 0.1)
				(type default)
			)
			(layer "F.Fab")
		)
		(fp_line
			(start 0.67945 0.3048)
			(end 0.120396 0.3048)
			(stroke
				(width 0.1)
				(type default)
			)
			(layer "F.Fab")
		)
		(fp_line
			(start -0.12065 0.2794)
			(end -0.12065 0.3048)
			(stroke
				(width 0.1)
				(type default)
			)
			(layer "F.Fab")
		)
		(fp_line
			(start 0.120396 0.2794)
			(end -0.12065 0.2794)
			(stroke
				(width 0.1)
				(type default)
			)
			(layer "F.Fab")
		)
		(fp_line
			(start -0.12065 -0.2794)
			(end 0.12065 -0.2794)
			(stroke
				(width 0.1)
				(type default)
			)
			(layer "F.Fab")
		)
		(fp_line
			(start 0.12065 -0.2794)
			(end 0.12065 -0.3048)
			(stroke
				(width 0.1)
				(type default)
			)
			(layer "F.Fab")
		)
		(fp_line
			(start 0.12065 -0.3048)
			(end 0.67945 -0.3048)
			(stroke
				(width 0.1)
				(type default)
			)
			(layer "F.Fab")
		)
		(fp_line
			(start 0.67945 -0.3048)
			(end 0.67945 0.3048)
			(stroke
				(width 0.1)
				(type default)
			)
			(layer "F.Fab")
		)
		(fp_line
			(start -0.67945 -0.305054)
			(end -0.12065 -0.305054)
			(stroke
				(width 0.1)
				(type default)
			)
			(layer "F.Fab")
		)
		(fp_line
			(start -0.12065 -0.305054)
			(end -0.12065 -0.2794)
			(stroke
				(width 0.1)
				(type default)
			)
			(layer "F.Fab")
		)
		(pad "1" smd circle
			(at -0.40005 0 270)
			(size 0 0)
			(layers "F.Cu" "F.Mask" "F.Paste")
			(net "PGPPA_AUX")
		)
		(pad "2" smd circle
			(at 0.40005 0 270)
			(size 0 0)
			(layers "F.Cu" "F.Mask" "F.Paste")
			(net "FM_ESPI_PLD_R_EN_BUF")
		)
	)
)
